(kicad_pcb
	(version 20260206)
	(generator "pcbnew")
	(generator_version "10.0")
	(general
		(thickness 1.6)
		(legacy_teardrops no)
	)
	(paper "A4")
	(title_block
		(title "netronome-mezz — pcbd0082-001_rev01_jul9_a.brd")
		(comment 1 "Open CloudServer (Microsoft) / footprints 337-340 of 714")
	)
	(layers
		(0 "F.Cu" signal "TOP")
		(4 "In1.Cu" signal "02_GND")
		(6 "In2.Cu" signal "03_SIG")
		(8 "In3.Cu" signal "04_SIG")
		(10 "In4.Cu" signal "05_GND")
		(12 "In5.Cu" signal "06_PWR1")
		(14 "In6.Cu" signal "07_SIG")
		(16 "In7.Cu" signal "08_SIG")
		(18 "In8.Cu" signal "09_GND")
		(2 "B.Cu" signal "BOTTOM")
		(9 "F.Adhes" user "F.Adhesive")
		(11 "B.Adhes" user "B.Adhesive")
		(13 "F.Paste" user "Package Geometry/Pastemask Top")
		(15 "B.Paste" user "Package Geometry/Pastemask Bottom")
		(5 "F.SilkS" user "Ref Des/Silkscreen Top")
		(7 "B.SilkS" user "Ref Des/Silkscreen Bottom")
		(1 "F.Mask" user "Board Geometry/Soldermask Top")
		(3 "B.Mask" user "Board Geometry/Soldermask Bottom")
		(17 "Dwgs.User" user "User.Drawings")
		(19 "Cmts.User" user "User.Comments")
		(21 "Eco1.User" user "User.Eco1")
		(23 "Eco2.User" user "User.Eco2")
		(25 "Edge.Cuts" user "Board Geometry/Outline")
		(27 "Margin" user)
		(31 "F.CrtYd" user "Package Geometry/Place Bound Top")
		(29 "B.CrtYd" user "Package Geometry/Place Bound Bottom")
		(35 "F.Fab" user "Ref Des/Assembly Top")
		(33 "B.Fab" user "Ref Des/Assembly Bottom")
		(45 "User.4" user "COMPVAL_TYPE_BOTTOM")
	)
	(footprint ""
		(layer "B.Cu")
		(at 48.2219 40.64 90)
		(property "Reference" "U5"
			(at -4.1275 2.5781 0)
			(unlocked yes)
			(layer "B.SilkS")
			(effects
				(font
					(size 1.27 0.9652)
					(thickness 0.1524)
				)
				(justify left mirror)
			)
		)
		(property "Value" "*"
			(at 0.2921 1.813154 90)
			(unlocked yes)
			(layer "B.Fab")
			(hide yes)
			(effects
				(font
					(size 0.7874 0.5842)
					(thickness 0.2032)
				)
				(justify left mirror)
			)
		)
		(property "Device Type" "TRAN0026"
			(at 0.2921 1.813154 90)
			(unlocked yes)
			(layer "B.Fab")
			(hide yes)
			(effects
				(font
					(size 0.7874 0.5842)
					(thickness 0.2032)
				)
				(justify left mirror)
			)
		)
		(duplicate_pad_numbers_are_jumpers no)
		(fp_line
			(start 3.302 -3.302)
			(end 3.302 -2.667)
			(stroke
				(width 0.1524)
				(type default)
			)
			(layer "B.SilkS")
		)
		(fp_line
			(start 2.667 -3.302)
			(end 3.302 -3.302)
			(stroke
				(width 0.1524)
				(type default)
			)
			(layer "B.SilkS")
		)
		(fp_line
			(start -3.302 2.667)
			(end -3.302 3.302)
			(stroke
				(width 0.1524)
				(type default)
			)
			(layer "B.SilkS")
		)
		(fp_line
			(start -3.302 3.302)
			(end -2.667 3.302)
			(stroke
				(width 0.1524)
				(type default)
			)
			(layer "B.SilkS")
		)
		(fp_circle
			(center 3.81508 -2.4638)
			(end 3.81508 -2.179803)
			(stroke
				(width 0.1524)
				(type default)
			)
			(fill no)
			(layer "B.SilkS")
		)
		(fp_poly
			(pts
				(xy 0 -2.032) (xy 0 -0.127) (xy -0.889 -0.127) (xy -0.889 -2.032)
			)
			(stroke
				(width 0)
				(type default)
			)
			(fill yes)
			(layer "B.Paste")
		)
		(fp_poly
			(pts
				(xy -2.032 -2.032) (xy -2.032 -0.127) (xy -1.143 -0.127) (xy -1.143 -2.032)
			)
			(stroke
				(width 0)
				(type default)
			)
			(fill yes)
			(layer "B.Paste")
		)
		(fp_poly
			(pts
				(xy 0 2.032) (xy 0 0.127) (xy -0.889 0.127) (xy -0.889 2.032)
			)
			(stroke
				(width 0)
				(type default)
			)
			(fill yes)
			(layer "B.Paste")
		)
		(fp_poly
			(pts
				(xy -2.032 2.032) (xy -2.032 0.127) (xy -1.143 0.127) (xy -1.143 2.032)
			)
			(stroke
				(width 0)
				(type default)
			)
			(fill yes)
			(layer "B.Paste")
		)
		(fp_poly
			(pts
				(xy -3.048 -3.937) (xy -3.048 3.937) (xy 3.937 3.937) (xy 3.937 2.54) (xy 3.937 -3.937)
			)
			(stroke
				(width 0)
				(type default)
			)
			(fill no)
			(layer "B.CrtYd")
		)
		(fp_line
			(start 3.048 -3.048)
			(end 3.048 3.048)
			(stroke
				(width 0.1524)
				(type default)
			)
			(layer "B.Fab")
		)
		(fp_line
			(start -3.048 -3.048)
			(end 3.048 -3.048)
			(stroke
				(width 0.1524)
				(type default)
			)
			(layer "B.Fab")
		)
		(fp_line
			(start 3.048 3.048)
			(end -3.048 3.048)
			(stroke
				(width 0.1524)
				(type default)
			)
			(layer "B.Fab")
		)
		(fp_line
			(start -3.048 3.048)
			(end -3.048 -3.048)
			(stroke
				(width 0.1524)
				(type default)
			)
			(layer "B.Fab")
		)
		(fp_circle
			(center 2.413 -2.413)
			(end 2.413 -2.129003)
			(stroke
				(width 0.1524)
				(type default)
			)
			(fill no)
			(layer "B.Fab")
		)
		(fp_text user "40"
			(at 1.905 -4.05257 270)
			(unlocked yes)
			(layer "B.SilkS")
			(effects
				(font
					(size 0.7874 0.5842)
					(thickness 0.127)
				)
				(justify left mirror)
			)
		)
		(fp_text user "20"
			(at -3.302 3.94843 270)
			(unlocked yes)
			(layer "B.SilkS")
			(effects
				(font
					(size 0.7874 0.5842)
					(thickness 0.127)
				)
				(justify left mirror)
			)
		)
		(pad "1" smd custom
			(at 2.9464 -2.250008)
			(size 0.06985 0.06985)
			(layers "B.Cu" "B.Mask" "B.Paste")
			(net "10N2256")
			(options
				(clearance outline)
				(anchor circle)
			)
			(primitives
				(gr_poly
					(pts
						(xy -0.1397 -0.4064) (xy -0.1397 0.3302) (xy -0.0635 0.4064) (xy 0.1397 0.4064) (xy 0.1397 -0.4064)
					)
					(width 0)
					(fill yes)
				)
			)
		)
		(pad "2" smd rect
			(at 2.9464 -1.750009)
			(size 0.2794 0.8128)
			(layers "B.Cu" "B.Mask" "B.Paste")
			(net "VDD_5.0V")
		)
		(pad "3" smd rect
			(at 2.9464 -1.25001)
			(size 0.2794 0.8128)
			(layers "B.Cu" "B.Mask" "B.Paste")
			(net "10N2225")
		)
		(pad "4" smd rect
			(at 2.9464 -0.750011)
			(size 0.2794 0.8128)
			(layers "B.Cu" "B.Mask" "B.Paste")
			(net "10N2232")
		)
		(pad "5" smd rect
			(at 2.9464 -0.250012)
			(size 0.2794 0.8128)
			(layers "B.Cu" "B.Mask" "B.Paste")
			(net "GND")
		)
		(pad "6" smd rect
			(at 2.9464 0.250012)
			(size 0.2794 0.8128)
			(layers "B.Cu" "B.Mask" "B.Paste")
			(net "GH_PHASE2")
		)
		(pad "7" smd rect
			(at 2.9464 0.750011)
			(size 0.2794 0.8128)
			(layers "B.Cu" "B.Mask" "B.Paste")
			(net "10N2259")
		)
		(pad "8" smd rect
			(at 2.9464 1.25001)
			(size 0.2794 0.8128)
			(layers "B.Cu" "B.Mask" "B.Paste")
			(net "EXT_12.0V")
		)
		(pad "9" smd rect
			(at 2.9464 1.750009)
			(size 0.2794 0.8128)
			(layers "B.Cu" "B.Mask" "B.Paste")
			(net "EXT_12.0V")
		)
		(pad "10" smd custom
			(at 2.9464 2.250008)
			(size 0.06985 0.06985)
			(layers "B.Cu" "B.Mask" "B.Paste")
			(net "EXT_12.0V")
			(options
				(clearance outline)
				(anchor circle)
			)
			(primitives
				(gr_poly
					(pts
						(xy 0.1397 -0.4064) (xy 0.1397 0.3302) (xy 0.0635 0.4064) (xy -0.1397 0.4064) (xy -0.1397 -0.4064)
					)
					(width 0)
					(fill yes)
				)
			)
		)
		(pad "11" smd custom
			(at 2.250008 2.9464 270)
			(size 0.06985 0.06985)
			(layers "B.Cu" "B.Mask" "B.Paste")
			(net "EXT_12.0V")
			(options
				(clearance outline)
				(anchor circle)
			)
			(primitives
				(gr_poly
					(pts
						(xy -0.1397 -0.4064) (xy -0.1397 0.3302) (xy -0.0635 0.4064) (xy 0.1397 0.4064) (xy 0.1397 -0.4064)
					)
					(width 0)
					(fill yes)
				)
			)
		)
		(pad "12" smd rect
			(at 1.750009 2.9464 270)
			(size 0.2794 0.8128)
			(layers "B.Cu" "B.Mask" "B.Paste")
			(net "EXT_12.0V")
		)
		(pad "13" smd rect
			(at 1.25001 2.9464 270)
			(size 0.2794 0.8128)
			(layers "B.Cu" "B.Mask" "B.Paste")
			(net "EXT_12.0V")
		)
		(pad "14" smd rect
			(at 0.750011 2.9464 270)
			(size 0.2794 0.8128)
			(layers "B.Cu" "B.Mask" "B.Paste")
			(net "EXT_12.0V")
		)
		(pad "15" smd rect
			(at 0.250012 2.9464 270)
			(size 0.2794 0.8128)
			(layers "B.Cu" "B.Mask" "B.Paste")
			(net "L_2_CORE_PHASE")
		)
		(pad "16" smd rect
			(at -0.250012 2.9464 270)
			(size 0.2794 0.8128)
			(layers "B.Cu" "B.Mask" "B.Paste")
			(net "GND")
		)
		(pad "17" smd rect
			(at -0.750011 2.9464 270)
			(size 0.2794 0.8128)
			(layers "B.Cu" "B.Mask" "B.Paste")
			(net "GND")
		)
		(pad "18" smd rect
			(at -1.25001 2.9464 270)
			(size 0.2794 0.8128)
			(layers "B.Cu" "B.Mask" "B.Paste")
			(net "GND")
		)
		(pad "19" smd rect
			(at -1.750009 2.9464 270)
			(size 0.2794 0.8128)
			(layers "B.Cu" "B.Mask" "B.Paste")
			(net "GND")
		)
		(pad "20" smd custom
			(at -2.250008 2.9464 270)
			(size 0.06985 0.06985)
			(layers "B.Cu" "B.Mask" "B.Paste")
			(net "GND")
			(options
				(clearance outline)
				(anchor circle)
			)
			(primitives
				(gr_poly
					(pts
						(xy 0.1397 -0.4064) (xy 0.1397 0.3302) (xy 0.0635 0.4064) (xy -0.1397 0.4064) (xy -0.1397 -0.4064)
					)
					(width 0)
					(fill yes)
				)
			)
		)
		(pad "21" smd custom
			(at -2.9464 2.250008 180)
			(size 0.06985 0.06985)
			(layers "B.Cu" "B.Mask" "B.Paste")
			(net "GND")
			(options
				(clearance outline)
				(anchor circle)
			)
			(primitives
				(gr_poly
					(pts
						(xy -0.1397 -0.4064) (xy -0.1397 0.3302) (xy -0.0635 0.4064) (xy 0.1397 0.4064) (xy 0.1397 -0.4064)
					)
					(width 0)
					(fill yes)
				)
			)
		)
		(pad "22" smd rect
			(at -2.9464 1.750009 180)
			(size 0.2794 0.8128)
			(layers "B.Cu" "B.Mask" "B.Paste")
			(net "GND")
		)
		(pad "23" smd rect
			(at -2.9464 1.25001 180)
			(size 0.2794 0.8128)
			(layers "B.Cu" "B.Mask" "B.Paste")
			(net "GND")
		)
		(pad "24" smd rect
			(at -2.9464 0.750011 180)
			(size 0.2794 0.8128)
			(layers "B.Cu" "B.Mask" "B.Paste")
			(net "GND")
		)
		(pad "25" smd rect
			(at -2.9464 0.250012 180)
			(size 0.2794 0.8128)
			(layers "B.Cu" "B.Mask" "B.Paste")
			(net "GND")
		)
		(pad "26" smd rect
			(at -2.9464 -0.250012 180)
			(size 0.2794 0.8128)
			(layers "B.Cu" "B.Mask" "B.Paste")
			(net "GND")
		)
		(pad "27" smd rect
			(at -2.9464 -0.750011 180)
			(size 0.2794 0.8128)
			(layers "B.Cu" "B.Mask" "B.Paste")
			(net "GND")
		)
		(pad "28" smd rect
			(at -2.9464 -1.25001 180)
			(size 0.2794 0.8128)
			(layers "B.Cu" "B.Mask" "B.Paste")
			(net "GND")
		)
		(pad "29" smd rect
			(at -2.9464 -1.750009 180)
			(size 0.2794 0.8128)
			(layers "B.Cu" "B.Mask" "B.Paste")
			(net "L_2_CORE_PHASE")
		)
		(pad "30" smd custom
			(at -2.9464 -2.250008 180)
			(size 0.06985 0.06985)
			(layers "B.Cu" "B.Mask" "B.Paste")
			(net "L_2_CORE_PHASE")
			(options
				(clearance outline)
				(anchor circle)
			)
			(primitives
				(gr_poly
					(pts
						(xy 0.1397 -0.4064) (xy 0.1397 0.3302) (xy 0.0635 0.4064) (xy -0.1397 0.4064) (xy -0.1397 -0.4064)
					)
					(width 0)
					(fill yes)
				)
			)
		)
		(pad "31" smd custom
			(at -2.250008 -2.9464 90)
			(size 0.06985 0.06985)
			(layers "B.Cu" "B.Mask" "B.Paste")
			(net "L_2_CORE_PHASE")
			(options
				(clearance outline)
				(anchor circle)
			)
			(primitives
				(gr_poly
					(pts
						(xy -0.1397 -0.4064) (xy -0.1397 0.3302) (xy -0.0635 0.4064) (xy 0.1397 0.4064) (xy 0.1397 -0.4064)
					)
					(width 0)
					(fill yes)
				)
			)
		)
		(pad "32" smd rect
			(at -1.750009 -2.9464 90)
			(size 0.2794 0.8128)
			(layers "B.Cu" "B.Mask" "B.Paste")
			(net "L_2_CORE_PHASE")
		)
		(pad "33" smd rect
			(at -1.25001 -2.9464 90)
			(size 0.2794 0.8128)
			(layers "B.Cu" "B.Mask" "B.Paste")
			(net "L_2_CORE_PHASE")
		)
		(pad "34" smd rect
			(at -0.750011 -2.9464 90)
			(size 0.2794 0.8128)
			(layers "B.Cu" "B.Mask" "B.Paste")
			(net "L_2_CORE_PHASE")
		)
		(pad "35" smd rect
			(at -0.250012 -2.9464 90)
			(size 0.2794 0.8128)
			(layers "B.Cu" "B.Mask" "B.Paste")
			(net "L_2_CORE_PHASE")
		)
		(pad "36" smd rect
			(at 0.250012 -2.9464 90)
			(size 0.2794 0.8128)
			(layers "B.Cu" "B.Mask" "B.Paste")
			(net "GL_PHASE2")
		)
		(pad "37" smd rect
			(at 0.750011 -2.9464 90)
			(size 0.2794 0.8128)
			(layers "B.Cu" "B.Mask" "B.Paste")
			(net "GND")
		)
		(pad "38" smd rect
			(at 1.25001 -2.9464 90)
			(size 0.2794 0.8128)
			(layers "B.Cu" "B.Mask" "B.Paste")
			(net "CORE_FB_PH2_THERM_L")
		)
		(pad "39" smd rect
			(at 1.750009 -2.9464 90)
			(size 0.2794 0.8128)
			(layers "B.Cu" "B.Mask" "B.Paste")
			(net "10N2235")
		)
		(pad "40" smd custom
			(at 2.250008 -2.9464 90)
			(size 0.06985 0.06985)
			(layers "B.Cu" "B.Mask" "B.Paste")
			(net "NFP_CORE_PWM2")
			(options
				(clearance outline)
				(anchor circle)
			)
			(primitives
				(gr_poly
					(pts
						(xy 0.1397 -0.4064) (xy 0.1397 0.3302) (xy 0.0635 0.4064) (xy -0.1397 0.4064) (xy -0.1397 -0.4064)
					)
					(width 0)
					(fill yes)
				)
			)
		)
		(pad "41" smd rect
			(at 1.4478 -1.1938 270)
			(size 1.4986 2.0066)
			(layers "B.Cu" "B.Mask" "B.Paste")
			(net "GND")
		)
		(pad "42" smd rect
			(at 1.4478 1.1938 270)
			(size 1.4986 2.0066)
			(layers "B.Cu" "B.Mask" "B.Paste")
			(net "EXT_12.0V")
		)
		(pad "43" smd rect
			(at -1.0033 0 270)
			(size 2.3876 4.3942)
			(layers "B.Cu" "B.Mask" "B.Paste")
			(net "L_2_CORE_PHASE")
		)
		(zone
			(layer "B.Cu")
			(hatch none 0.5)
			(connect_pads
				(clearance 0)
			)
			(min_thickness 0.25)
			(keepout
				(tracks allowed)
				(vias not_allowed)
				(pads allowed)
				(copperpour not_allowed)
				(footprints allowed)
			)
			(placement
				(enabled no)
				(sheetname "")
			)
			(fill
				(thermal_gap 0.5)
				(thermal_bridge_width 0.5)
				(island_removal_mode 0)
			)
			(polygon
				(pts
					(arc
						(start 46.118297 36.82492)
						(mid 45.397903 36.82492)
						(end 46.118297 36.82492)
					)
				)
			)
		)
	)
	(footprint ""
		(layer "B.Cu")
		(at 5.08 3.81 90)
		(property "Reference" "R277"
			(at 0 0 90)
			(layer "B.SilkS")
			(hide yes)
			(effects
				(font
					(size 1.27 1.27)
				)
				(justify mirror)
			)
		)
		(property "Value" "240"
			(at 0.148158 1.3462 0)
			(unlocked yes)
			(layer "B.Fab")
			(hide yes)
			(effects
				(font
					(size 1.27 0.9652)
					(thickness 0.000001)
				)
				(justify left mirror)
			)
		)
		(property "Device Type" "REST0009"
			(at 0.148158 1.3462 0)
			(unlocked yes)
			(layer "B.Fab")
			(hide yes)
			(effects
				(font
					(size 1.27 0.9652)
					(thickness 0.000001)
				)
				(justify left mirror)
			)
		)
		(duplicate_pad_numbers_are_jumpers no)
		(fp_poly
			(pts
				(xy -0.635 1.0668) (xy -0.635 -1.0668) (xy 0.635 -1.0668) (xy 0.635 1.0668)
			)
			(stroke
				(width 0)
				(type default)
			)
			(fill no)
			(layer "B.CrtYd")
		)
		(fp_line
			(start 0.254 -0.508)
			(end -0.254 -0.508)
			(stroke
				(width 0.0254)
				(type default)
			)
			(layer "B.Fab")
		)
		(fp_line
			(start -0.254 -0.508)
			(end -0.254 0.508)
			(stroke
				(width 0.0254)
				(type default)
			)
			(layer "B.Fab")
		)
		(fp_line
			(start 0.254 0.508)
			(end 0.254 -0.508)
			(stroke
				(width 0.0254)
				(type default)
			)
			(layer "B.Fab")
		)
		(fp_line
			(start -0.254 0.508)
			(end 0.254 0.508)
			(stroke
				(width 0.0254)
				(type default)
			)
			(layer "B.Fab")
		)
		(pad "1" smd rect
			(at 0 -0.4191 270)
			(size 0.508 0.5334)
			(layers "B.Cu" "B.Mask" "B.Paste")
			(net "PWR_GOOD_LED_L")
		)
		(pad "2" smd rect
			(at 0 0.4191 270)
			(size 0.508 0.5334)
			(layers "B.Cu" "B.Mask" "B.Paste")
			(net "9N2141")
		)
		(zone
			(layer "B.Cu")
			(hatch none 0.5)
			(connect_pads
				(clearance 0)
			)
			(min_thickness 0.25)
			(keepout
				(tracks not_allowed)
				(vias allowed)
				(pads allowed)
				(copperpour not_allowed)
				(footprints allowed)
			)
			(placement
				(enabled no)
				(sheetname "")
			)
			(fill
				(thermal_gap 0.5)
				(thermal_bridge_width 0.5)
				(island_removal_mode 0)
			)
			(polygon
				(pts
					(xy 5.0546 3.8354) (xy 5.1054 3.8354) (xy 5.1054 3.7846) (xy 5.0546 3.7846)
				)
			)
		)
	)
	(footprint ""
		(layer "B.Cu")
		(at 56.236997 27.541982)
		(property "Reference" "C163"
			(at 0 0 0)
			(layer "B.SilkS")
			(hide yes)
			(effects
				(font
					(size 1.27 1.27)
				)
				(justify mirror)
			)
		)
		(property "Value" ""
			(at 0 0 0)
			(layer "B.Fab")
			(effects
				(font
					(size 1.27 1.27)
				)
				(justify mirror)
			)
		)
		(duplicate_pad_numbers_are_jumpers no)
		(fp_circle
			(center 0 0)
			(end 0.104648 0)
			(stroke
				(width 0.1016)
				(type default)
			)
			(fill no)
			(layer "B.SilkS")
		)
		(fp_poly
			(pts
				(xy 0.381 -0.889) (xy 0.381 0.889) (xy -0.381 0.889) (xy -0.381 -0.889)
			)
			(stroke
				(width 0)
				(type default)
			)
			(fill no)
			(layer "B.CrtYd")
		)
		(fp_line
			(start -0.508 -1.016)
			(end -0.508 1.016)
			(stroke
				(width 0.0254)
				(type default)
			)
			(layer "B.Fab")
		)
		(fp_line
			(start -0.508 1.016)
			(end 0.508 1.016)
			(stroke
				(width 0.0254)
				(type default)
			)
			(layer "B.Fab")
		)
		(fp_line
			(start 0.254 -1.016)
			(end -0.508 -1.016)
			(stroke
				(width 0.0254)
				(type default)
			)
			(layer "B.Fab")
		)
		(fp_line
			(start 0.508 -1.016)
			(end 0.254 -1.016)
			(stroke
				(width 0.0254)
				(type default)
			)
			(layer "B.Fab")
		)
		(fp_line
			(start 0.508 1.016)
			(end 0.508 -1.016)
			(stroke
				(width 0.0254)
				(type default)
			)
			(layer "B.Fab")
		)
		(pad "1" smd custom
			(at 0 -0.500126 180)
			(size 0.127 0.127)
			(layers "B.Cu" "B.Mask" "B.Paste")
			(net "VDD_CORE")
			(options
				(clearance outline)
				(anchor circle)
			)
			(primitives
				(gr_poly
					(pts
						(xy -0.1778 0.254) (xy 0.1778 0.254) (xy 0.254 0.1778) (xy 0.254 -0.1778) (xy 0.1778 -0.254) (xy -0.1778 -0.254)
						(xy -0.254 -0.1778) (xy -0.254 0.1778)
					)
					(width 0)
					(fill yes)
				)
			)
		)
		(pad "2" smd custom
			(at 0 0.500126 180)
			(size 0.127 0.127)
			(layers "B.Cu" "B.Mask" "B.Paste")
			(net "GND")
			(options
				(clearance outline)
				(anchor circle)
			)
			(primitives
				(gr_poly
					(pts
						(xy -0.1778 0.254) (xy 0.1778 0.254) (xy 0.254 0.1778) (xy 0.254 -0.1778) (xy 0.1778 -0.254) (xy -0.1778 -0.254)
						(xy -0.254 -0.1778) (xy -0.254 0.1778)
					)
					(width 0)
					(fill yes)
				)
			)
		)
	)
	(footprint ""
		(layer "B.Cu")
		(at 84.250987 18.255996)
		(property "Reference" "V2_A-A14"
			(at 0 0 0)
			(layer "B.SilkS")
			(hide yes)
			(effects
				(font
					(size 1.27 1.27)
				)
				(justify mirror)
			)
		)
		(property "Value" ""
			(at 0 0 0)
			(layer "B.Fab")
			(effects
				(font
					(size 1.27 1.27)
				)
				(justify mirror)
			)
		)
		(duplicate_pad_numbers_are_jumpers no)
		(pad "1" thru_hole circle
			(at 0 0 180)
			(size 0.4572 0.4572)
			(drill 0.20574)
			(layers "*.Cu" "*.Mask")
			(remove_unused_layers no)
			(net "DDR0_32A_A14")
			(clearance 0.1143)
			(thermal_gap 0.1143)
		)
	)
)
